# BASEBOARD_FAB2 (Tioga Pass) — schematic netlist excerpt (pin names and nets, part order shuffled) for the footprints in the layout excerpt that follows; sources: Cadence DE-HDL packaged netlist, KiCad conversion of Wiwynn_Tioga_Pass_MB.brd

CT38  CAP  1000PF 50V 10% X7R  pkg 0402LF  page 203 : A = VR_PVCCIN_CPU0_PHASE3 ; B = VR_PVCCIN_CPU0_PHASE3_RC
R1C5  RES  0.0 5% CHIP  pkg 0402  page 210 : A = VSENSE_PVSA_CPU1_N ; B = VSENSE_PVSA_CPU1_SKT_VRTN
C8E11  SC22U16V5MX-4-GP  20%  pkg SMD-BCG5  page 240 : \1\ = VR_FET_SW_P12V_STBY_P3V3_STBY ; \2\ = GND

(kicad_pcb
	(version 20260206)
	(generator "pcbnew")
	(generator_version "10.0")
	(general
		(thickness 1.6)
		(legacy_teardrops no)
	)
	(paper "A4")
	(title_block
		(title "Wiwynn_Tioga_Pass_MB.brd")
		(comment 1 "Tioga Pass / footprints 256-258 of 4770")
	)
	(layers
		(0 "F.Cu" signal "TOP")
		(4 "In1.Cu" signal "L2GND")
		(6 "In2.Cu" signal "L3")
		(8 "In3.Cu" signal "L4GND")
		(10 "In4.Cu" signal "L5")
		(12 "In5.Cu" signal "L6GND")
		(14 "In6.Cu" signal "L7VCC")
		(16 "In7.Cu" signal "L8VCC")
		(18 "In8.Cu" signal "L9GND")
		(20 "In9.Cu" signal "L10")
		(22 "In10.Cu" signal "L11GND")
		(24 "In11.Cu" signal "L12")
		(26 "In12.Cu" signal "L13GND")
		(2 "B.Cu" signal "BOTTOM")
		(9 "F.Adhes" user "F.Adhesive")
		(11 "B.Adhes" user "B.Adhesive")
		(13 "F.Paste" user "Package Geometry/Pastemask Top")
		(15 "B.Paste" user "Package Geometry/Pastemask Bottom")
		(5 "F.SilkS" user "Ref Des/Silkscreen Top")
		(7 "B.SilkS" user "Ref Des/Silkscreen Bottom")
		(1 "F.Mask" user "Board Geometry/Soldermask Top")
		(3 "B.Mask" user "Board Geometry/Soldermask Bottom")
		(17 "Dwgs.User" user "User.Drawings")
		(19 "Cmts.User" user "User.Comments")
		(21 "Eco1.User" user "User.Eco1")
		(23 "Eco2.User" user "User.Eco2")
		(25 "Edge.Cuts" user "Board Geometry/Outline")
		(27 "Margin" user)
		(31 "F.CrtYd" user "Package Geometry/Place Bound Top")
		(29 "B.CrtYd" user "Package Geometry/Place Bound Bottom")
		(35 "F.Fab" user "Ref Des/Assembly Top")
		(33 "B.Fab" user "Ref Des/Assembly Bottom")
	)
	(footprint ""
		(layer "F.Cu")
		(at 478.0026 -22.4028)
		(property "Reference" "C8E11"
			(at 0 0 0)
			(layer "F.SilkS")
			(hide yes)
			(effects
				(font
					(size 1.27 1.27)
				)
			)
		)
		(property "Value" "*"
			(at -0.0762 -6.2357 0)
			(unlocked yes)
			(layer "F.Fab")
			(hide yes)
			(effects
				(font
					(size 1.27 1.016)
					(thickness 0.1524)
				)
			)
		)
		(property "Device Type" "SC22U16V5MX-4-GP_SMD-BCG5-SC22A"
			(at -0.0762 -8.2677 0)
			(unlocked yes)
			(layer "F.Fab")
			(hide yes)
			(effects
				(font
					(size 1.27 1.016)
					(thickness 0.1524)
				)
			)
		)
		(duplicate_pad_numbers_are_jumpers no)
		(fp_line
			(start 0.635 0)
			(end -0.635 0)
			(stroke
				(width 0.508)
				(type default)
			)
			(layer "F.SilkS")
		)
		(fp_rect
			(start -0.9652 1.778)
			(end 0.9652 -1.778)
			(stroke
				(width 0)
				(type default)
			)
			(fill no)
			(layer "F.CrtYd")
		)
		(fp_poly
			(pts
				(xy -0.9652 -1.778) (xy 0.9652 -1.778) (xy 0.9652 1.778) (xy -0.9652 1.778)
			)
			(stroke
				(width 0)
				(type default)
			)
			(fill no)
			(layer "F.Fab")
		)
		(pad "1" smd rect
			(at 0 -0.9652)
			(size 1.397 1.143)
			(layers "F.Cu" "F.Mask" "F.Paste")
			(net "VR_FET_SW_P12V_STBY_P3V3_STBY")
		)
		(pad "2" smd rect
			(at 0 0.9652)
			(size 1.397 1.143)
			(layers "F.Cu" "F.Mask" "F.Paste")
			(net "GND")
		)
	)
	(footprint ""
		(layer "F.Cu")
		(at 204.6224 -69.342 -90)
		(property "Reference" "CT38"
			(at -0.8382 -0.67818 270)
			(unlocked yes)
			(layer "F.SilkS")
			(effects
				(font
					(size 0.4064 0.254)
					(thickness 0.1524)
				)
				(justify left)
			)
		)
		(property "Value" ""
			(at 0 0 270)
			(layer "F.Fab")
			(effects
				(font
					(size 1.27 1.27)
				)
			)
		)
		(duplicate_pad_numbers_are_jumpers no)
		(fp_poly
			(pts
				(xy 0.3048 -0.1016) (xy 0.3048 0.9906) (xy -0.3048 0.9906) (xy -0.3048 -0.1016)
			)
			(stroke
				(width 0)
				(type default)
			)
			(fill no)
			(layer "F.CrtYd")
		)
		(fp_line
			(start -0.3048 0.9906)
			(end 0.3048 0.9906)
			(stroke
				(width 0.1)
				(type default)
			)
			(layer "F.Fab")
		)
		(fp_line
			(start 0.3048 0.9906)
			(end 0.3048 -0.1016)
			(stroke
				(width 0.1)
				(type default)
			)
			(layer "F.Fab")
		)
		(fp_line
			(start -0.3048 -0.1016)
			(end -0.3048 0.9906)
			(stroke
				(width 0.1)
				(type default)
			)
			(layer "F.Fab")
		)
		(fp_line
			(start 0.3048 -0.1016)
			(end -0.3048 -0.1016)
			(stroke
				(width 0.1)
				(type default)
			)
			(layer "F.Fab")
		)
		(pad "1" smd rect
			(at 0 0 270)
			(size 0.508 0.508)
			(layers "F.Cu" "F.Mask" "F.Paste")
			(net "VR_PVCCIN_CPU0_PHASE3")
		)
		(pad "2" smd rect
			(at 0 0.889 270)
			(size 0.508 0.508)
			(layers "F.Cu" "F.Mask" "F.Paste")
			(net "VR_PVCCIN_CPU0_PHASE3_RC")
		)
		(zone
			(layer "F.Cu")
			(hatch none 0.5)
			(connect_pads
				(clearance 0)
			)
			(min_thickness 0.25)
			(keepout
				(tracks not_allowed)
				(vias allowed)
				(pads allowed)
				(copperpour not_allowed)
				(footprints allowed)
			)
			(placement
				(enabled no)
				(sheetname "")
			)
			(fill
				(thermal_gap 0.5)
				(thermal_bridge_width 0.5)
				(island_removal_mode 0)
			)
			(polygon
				(pts
					(xy 203.9874 -69.596) (xy 203.9874 -69.088) (xy 204.3684 -69.088) (xy 204.3684 -69.596)
				)
			)
		)
		(zone
			(layer "F.Cu")
			(hatch none 0.5)
			(connect_pads
				(clearance 0)
			)
			(min_thickness 0.25)
			(keepout
				(tracks allowed)
				(vias not_allowed)
				(pads allowed)
				(copperpour not_allowed)
				(footprints allowed)
			)
			(placement
				(enabled no)
				(sheetname "")
			)
			(fill
				(thermal_gap 0.5)
				(thermal_bridge_width 0.5)
				(island_removal_mode 0)
			)
			(polygon
				(pts
					(xy 204.3684 -69.596) (xy 204.3684 -69.088) (xy 203.9874 -69.088) (xy 203.9874 -69.596)
				)
			)
		)
	)
	(footprint ""
		(layer "F.Cu")
		(at 40.60825 -103.491284 90)
		(property "Reference" "R1C5"
			(at 0 0 90)
			(layer "F.SilkS")
			(hide yes)
			(effects
				(font
					(size 1.27 1.27)
				)
			)
		)
		(property "Value" ""
			(at 0 0 90)
			(layer "F.Fab")
			(effects
				(font
					(size 1.27 1.27)
				)
			)
		)
		(duplicate_pad_numbers_are_jumpers no)
		(fp_poly
			(pts
				(xy -0.2794 -0.1016) (xy 0.2794 -0.1016) (xy 0.2794 0.9906) (xy -0.2794 0.9906)
			)
			(stroke
				(width 0)
				(type default)
			)
			(fill no)
			(layer "F.CrtYd")
		)
		(fp_line
			(start 0.2794 -0.1016)
			(end -0.2794 -0.1016)
			(stroke
				(width 0.1)
				(type default)
			)
			(layer "F.Fab")
		)
		(fp_line
			(start -0.2794 -0.1016)
			(end -0.2794 0.9906)
			(stroke
				(width 0.1)
				(type default)
			)
			(layer "F.Fab")
		)
		(fp_line
			(start 0.2794 0.9906)
			(end 0.2794 -0.1016)
			(stroke
				(width 0.1)
				(type default)
			)
			(layer "F.Fab")
		)
		(fp_line
			(start -0.2794 0.9906)
			(end 0.2794 0.9906)
			(stroke
				(width 0.1)
				(type default)
			)
			(layer "F.Fab")
		)
		(pad "1" smd rect
			(at 0 0 90)
			(size 0.508 0.508)
			(layers "F.Cu" "F.Mask" "F.Paste")
			(net "VSENSE_PVSA_CPU1_N")
		)
		(pad "2" smd rect
			(at 0 0.889 90)
			(size 0.508 0.508)
			(layers "F.Cu" "F.Mask" "F.Paste")
			(net "VSENSE_PVSA_CPU1_SKT_VRTN")
		)
		(zone
			(layer "F.Cu")
			(hatch none 0.5)
			(connect_pads
				(clearance 0)
			)
			(min_thickness 0.25)
			(keepout
				(tracks allowed)
				(vias not_allowed)
				(pads allowed)
				(copperpour not_allowed)
				(footprints allowed)
			)
			(placement
				(enabled no)
				(sheetname "")
			)
			(fill
				(thermal_gap 0.5)
				(thermal_bridge_width 0.5)
				(island_removal_mode 0)
			)
			(polygon
				(pts
					(xy 40.86225 -103.237284) (xy 40.86225 -103.745284) (xy 41.24325 -103.745284) (xy 41.24325 -103.237284)
				)
			)
		)
		(zone
			(layer "F.Cu")
			(hatch none 0.5)
			(connect_pads
				(clearance 0)
			)
			(min_thickness 0.25)
			(keepout
				(tracks not_allowed)
				(vias allowed)
				(pads allowed)
				(copperpour not_allowed)
				(footprints allowed)
			)
			(placement
				(enabled no)
				(sheetname "")
			)
			(fill
				(thermal_gap 0.5)
				(thermal_bridge_width 0.5)
				(island_removal_mode 0)
			)
			(polygon
				(pts
					(xy 41.24325 -103.237284) (xy 41.24325 -103.745284) (xy 40.86225 -103.745284) (xy 40.86225 -103.237284)
				)
			)
		)
	)
)
